# S9S_MB_2U (Grand Teton) — schematic netlist excerpt (pin names and nets, part order shuffled) for the footprints in the layout excerpt that follows; sources: Cadence DE-HDL packaged netlist, KiCad conversion of 03242023_DA0F0TMBIJ0_F0T_Motherboard_J_brd_V01_OCP.brd

PR3812  Q_RES  15K 1% CHIP  pkg 0402LF  page 162 : A = P3V3_OCP_OV_2 ; B = GND
C813  Q_CAP_DIFFBUS  DIFF BUS_0.22UF 6.3V 20% X6S  pkg C0201  page 175 : \1\ = P5E_CPU1_PE1_TX_C_DP<12> ; \2\ = P5E_CPU1_PE1_TX_DP<12>
C2013  Q_CAP  0.1UF 25V 10% X7R  pkg 0402  page 172 : A = P3V3_AUX ; B = GND

(kicad_pcb
	(version 20260206)
	(generator "pcbnew")
	(generator_version "10.0")
	(general
		(thickness 1.6)
		(legacy_teardrops no)
	)
	(paper "A4")
	(title_block
		(title "03242023_DA0F0TMBIJ0_F0T_Motherboard_J_brd_V01_OCP.brd")
		(comment 1 "Grand Teton / footprints 319-321 of 6105")
	)
	(layers
		(0 "F.Cu" signal "TOP")
		(4 "In1.Cu" signal "GND")
		(6 "In2.Cu" signal "IN1")
		(8 "In3.Cu" signal "GND1")
		(10 "In4.Cu" signal "IN2")
		(12 "In5.Cu" signal "GND2")
		(14 "In6.Cu" signal "IN3")
		(16 "In7.Cu" signal "GND3")
		(18 "In8.Cu" signal "VCC")
		(20 "In9.Cu" signal "VCC1")
		(22 "In10.Cu" signal "GND4")
		(24 "In11.Cu" signal "IN4")
		(26 "In12.Cu" signal "GND5")
		(28 "In13.Cu" signal "IN5")
		(30 "In14.Cu" signal "GND6")
		(32 "In15.Cu" signal "IN6")
		(34 "In16.Cu" signal "GND7")
		(2 "B.Cu" signal "BOTTOM")
		(9 "F.Adhes" user "F.Adhesive")
		(11 "B.Adhes" user "B.Adhesive")
		(13 "F.Paste" user "Package Geometry/Pastemask Top")
		(15 "B.Paste" user "Package Geometry/Pastemask Bottom")
		(5 "F.SilkS" user "Ref Des/Silkscreen Top")
		(7 "B.SilkS" user "Ref Des/Silkscreen Bottom")
		(1 "F.Mask" user "Board Geometry/Soldermask Top")
		(3 "B.Mask" user "Board Geometry/Soldermask Bottom")
		(17 "Dwgs.User" user "User.Drawings")
		(19 "Cmts.User" user "User.Comments")
		(21 "Eco1.User" user "User.Eco1")
		(23 "Eco2.User" user "User.Eco2")
		(25 "Edge.Cuts" user "Board Geometry/Outline")
		(27 "Margin" user)
		(31 "F.CrtYd" user "Package Geometry/Place Bound Top")
		(29 "B.CrtYd" user "Package Geometry/Place Bound Bottom")
		(35 "F.Fab" user "Ref Des/Assembly Top")
		(33 "B.Fab" user "Ref Des/Assembly Bottom")
	)
	(footprint ""
		(layer "F.Cu")
		(at 155.690824 -51.531012)
		(property "Reference" "C2013"
			(at 0 0 0)
			(layer "F.SilkS")
			(hide yes)
			(effects
				(font
					(size 1.27 1.27)
				)
			)
		)
		(property "Value" ""
			(at 0 0 0)
			(layer "F.Fab")
			(effects
				(font
					(size 1.27 1.27)
				)
			)
		)
		(duplicate_pad_numbers_are_jumpers no)
		(fp_line
			(start -0.7874 -0.4064)
			(end 0.7874 -0.4064)
			(stroke
				(width 0.1524)
				(type default)
			)
			(layer "F.SilkS")
		)
		(fp_line
			(start -0.7874 0.4064)
			(end -0.7874 -0.4064)
			(stroke
				(width 0.1524)
				(type default)
			)
			(layer "F.SilkS")
		)
		(fp_line
			(start 0.7874 -0.4064)
			(end 0.7874 0.4064)
			(stroke
				(width 0.1524)
				(type default)
			)
			(layer "F.SilkS")
		)
		(fp_line
			(start 0.7874 0.4064)
			(end -0.7874 0.4064)
			(stroke
				(width 0.1524)
				(type default)
			)
			(layer "F.SilkS")
		)
		(fp_line
			(start -0.67945 -0.305054)
			(end -0.12065 -0.305054)
			(stroke
				(width 0.1)
				(type default)
			)
			(layer "F.Fab")
		)
		(fp_line
			(start -0.67945 0.3048)
			(end -0.67945 -0.305054)
			(stroke
				(width 0.1)
				(type default)
			)
			(layer "F.Fab")
		)
		(fp_line
			(start -0.12065 -0.305054)
			(end -0.12065 -0.2794)
			(stroke
				(width 0.1)
				(type default)
			)
			(layer "F.Fab")
		)
		(fp_line
			(start -0.12065 -0.2794)
			(end 0.12065 -0.2794)
			(stroke
				(width 0.1)
				(type default)
			)
			(layer "F.Fab")
		)
		(fp_line
			(start -0.12065 0.2794)
			(end -0.12065 0.3048)
			(stroke
				(width 0.1)
				(type default)
			)
			(layer "F.Fab")
		)
		(fp_line
			(start -0.12065 0.3048)
			(end -0.67945 0.3048)
			(stroke
				(width 0.1)
				(type default)
			)
			(layer "F.Fab")
		)
		(fp_line
			(start 0.120396 0.2794)
			(end -0.12065 0.2794)
			(stroke
				(width 0.1)
				(type default)
			)
			(layer "F.Fab")
		)
		(fp_line
			(start 0.120396 0.3048)
			(end 0.120396 0.2794)
			(stroke
				(width 0.1)
				(type default)
			)
			(layer "F.Fab")
		)
		(fp_line
			(start 0.12065 -0.3048)
			(end 0.67945 -0.3048)
			(stroke
				(width 0.1)
				(type default)
			)
			(layer "F.Fab")
		)
		(fp_line
			(start 0.12065 -0.2794)
			(end 0.12065 -0.3048)
			(stroke
				(width 0.1)
				(type default)
			)
			(layer "F.Fab")
		)
		(fp_line
			(start 0.67945 -0.3048)
			(end 0.67945 0.3048)
			(stroke
				(width 0.1)
				(type default)
			)
			(layer "F.Fab")
		)
		(fp_line
			(start 0.67945 0.3048)
			(end 0.120396 0.3048)
			(stroke
				(width 0.1)
				(type default)
			)
			(layer "F.Fab")
		)
		(pad "1" smd circle
			(at -0.40005 0)
			(size 0 0)
			(layers "F.Cu" "F.Mask" "F.Paste")
			(net "P3V3_AUX")
		)
		(pad "2" smd circle
			(at 0.40005 0)
			(size 0 0)
			(layers "F.Cu" "F.Mask" "F.Paste")
			(net "GND")
		)
	)
	(footprint ""
		(layer "F.Cu")
		(at 24.804878 -17.623536 90)
		(property "Reference" "C813"
			(at 0 0 90)
			(layer "F.SilkS")
			(hide yes)
			(effects
				(font
					(size 1.27 1.27)
				)
			)
		)
		(property "Value" ""
			(at 0 0 90)
			(layer "F.Fab")
			(effects
				(font
					(size 1.27 1.27)
				)
			)
		)
		(duplicate_pad_numbers_are_jumpers no)
		(fp_line
			(start 0.299974 -0.150114)
			(end 0.299974 0.150114)
			(stroke
				(width 0.1)
				(type default)
			)
			(layer "F.Fab")
		)
		(fp_line
			(start -0.299974 -0.150114)
			(end 0.299974 -0.150114)
			(stroke
				(width 0.1)
				(type default)
			)
			(layer "F.Fab")
		)
		(fp_line
			(start 0.299974 0.150114)
			(end -0.299974 0.150114)
			(stroke
				(width 0.1)
				(type default)
			)
			(layer "F.Fab")
		)
		(fp_line
			(start -0.299974 0.150114)
			(end -0.299974 -0.150114)
			(stroke
				(width 0.1)
				(type default)
			)
			(layer "F.Fab")
		)
		(pad "1" smd rect
			(at -0.2667 0 90)
			(size 0.3048 0.381)
			(layers "F.Cu" "F.Mask" "F.Paste")
			(net "P5E_CPU1_PE1_TX_C_DP<12>")
		)
		(pad "2" smd rect
			(at 0.2667 0 90)
			(size 0.3048 0.381)
			(layers "F.Cu" "F.Mask" "F.Paste")
			(net "P5E_CPU1_PE1_TX_DP<12>")
		)
	)
	(footprint ""
		(layer "F.Cu")
		(at 79.75473 -59.372246 90)
		(property "Reference" "PR3812"
			(at 0 0 90)
			(layer "F.SilkS")
			(hide yes)
			(effects
				(font
					(size 1.27 1.27)
				)
			)
		)
		(property "Value" ""
			(at 0 0 90)
			(layer "F.Fab")
			(effects
				(font
					(size 1.27 1.27)
				)
			)
		)
		(duplicate_pad_numbers_are_jumpers no)
		(fp_line
			(start 0.7874 -0.4064)
			(end 0.7874 0.4064)
			(stroke
				(width 0.1524)
				(type default)
			)
			(layer "F.SilkS")
		)
		(fp_line
			(start -0.7874 -0.4064)
			(end 0.7874 -0.4064)
			(stroke
				(width 0.1524)
				(type default)
			)
			(layer "F.SilkS")
		)
		(fp_line
			(start 0.7874 0.4064)
			(end -0.7874 0.4064)
			(stroke
				(width 0.1524)
				(type default)
			)
			(layer "F.SilkS")
		)
		(fp_line
			(start -0.7874 0.4064)
			(end -0.7874 -0.4064)
			(stroke
				(width 0.1524)
				(type default)
			)
			(layer "F.SilkS")
		)
		(fp_line
			(start -0.12065 -0.305054)
			(end -0.12065 -0.2794)
			(stroke
				(width 0.1)
				(type default)
			)
			(layer "F.Fab")
		)
		(fp_line
			(start -0.67945 -0.305054)
			(end -0.12065 -0.305054)
			(stroke
				(width 0.1)
				(type default)
			)
			(layer "F.Fab")
		)
		(fp_line
			(start 0.67945 -0.3048)
			(end 0.67945 0.3048)
			(stroke
				(width 0.1)
				(type default)
			)
			(layer "F.Fab")
		)
		(fp_line
			(start 0.12065 -0.3048)
			(end 0.67945 -0.3048)
			(stroke
				(width 0.1)
				(type default)
			)
			(layer "F.Fab")
		)
		(fp_line
			(start 0.12065 -0.2794)
			(end 0.12065 -0.3048)
			(stroke
				(width 0.1)
				(type default)
			)
			(layer "F.Fab")
		)
		(fp_line
			(start -0.12065 -0.2794)
			(end 0.12065 -0.2794)
			(stroke
				(width 0.1)
				(type default)
			)
			(layer "F.Fab")
		)
		(fp_line
			(start 0.120396 0.2794)
			(end -0.12065 0.2794)
			(stroke
				(width 0.1)
				(type default)
			)
			(layer "F.Fab")
		)
		(fp_line
			(start -0.12065 0.2794)
			(end -0.12065 0.3048)
			(stroke
				(width 0.1)
				(type default)
			)
			(layer "F.Fab")
		)
		(fp_line
			(start 0.67945 0.3048)
			(end 0.120396 0.3048)
			(stroke
				(width 0.1)
				(type default)
			)
			(layer "F.Fab")
		)
		(fp_line
			(start 0.120396 0.3048)
			(end 0.120396 0.2794)
			(stroke
				(width 0.1)
				(type default)
			)
			(layer "F.Fab")
		)
		(fp_line
			(start -0.12065 0.3048)
			(end -0.67945 0.3048)
			(stroke
				(width 0.1)
				(type default)
			)
			(layer "F.Fab")
		)
		(fp_line
			(start -0.67945 0.3048)
			(end -0.67945 -0.305054)
			(stroke
				(width 0.1)
				(type default)
			)
			(layer "F.Fab")
		)
		(pad "1" smd circle
			(at -0.40005 0 90)
			(size 0 0)
			(layers "F.Cu" "F.Mask" "F.Paste")
			(net "P3V3_OCP_OV_2")
		)
		(pad "2" smd circle
			(at 0.40005 0 90)
			(size 0 0)
			(layers "F.Cu" "F.Mask" "F.Paste")
			(net "GND")
		)
	)
)
